(kicad_pcb
	(version 20260206)
	(generator "pcbnew")
	(generator_version "10.0")
	(general
		(thickness 1.6)
		(legacy_teardrops no)
	)
	(paper "A4")
	(title_block
		(title "03242023_DA0F0TMBIJ0_F0T_Motherboard_J_brd_V01_OCP.brd")
		(comment 1 "Grand Teton / footprints 2221-2226 of 6105")
	)
	(layers
		(0 "F.Cu" signal "TOP")
		(4 "In1.Cu" signal "GND")
		(6 "In2.Cu" signal "IN1")
		(8 "In3.Cu" signal "GND1")
		(10 "In4.Cu" signal "IN2")
		(12 "In5.Cu" signal "GND2")
		(14 "In6.Cu" signal "IN3")
		(16 "In7.Cu" signal "GND3")
		(18 "In8.Cu" signal "VCC")
		(20 "In9.Cu" signal "VCC1")
		(22 "In10.Cu" signal "GND4")
		(24 "In11.Cu" signal "IN4")
		(26 "In12.Cu" signal "GND5")
		(28 "In13.Cu" signal "IN5")
		(30 "In14.Cu" signal "GND6")
		(32 "In15.Cu" signal "IN6")
		(34 "In16.Cu" signal "GND7")
		(2 "B.Cu" signal "BOTTOM")
		(9 "F.Adhes" user "F.Adhesive")
		(11 "B.Adhes" user "B.Adhesive")
		(13 "F.Paste" user "Package Geometry/Pastemask Top")
		(15 "B.Paste" user "Package Geometry/Pastemask Bottom")
		(5 "F.SilkS" user "Ref Des/Silkscreen Top")
		(7 "B.SilkS" user "Ref Des/Silkscreen Bottom")
		(1 "F.Mask" user "Board Geometry/Soldermask Top")
		(3 "B.Mask" user "Board Geometry/Soldermask Bottom")
		(17 "Dwgs.User" user "User.Drawings")
		(19 "Cmts.User" user "User.Comments")
		(21 "Eco1.User" user "User.Eco1")
		(23 "Eco2.User" user "User.Eco2")
		(25 "Edge.Cuts" user "Board Geometry/Outline")
		(27 "Margin" user)
		(31 "F.CrtYd" user "Package Geometry/Place Bound Top")
		(29 "B.CrtYd" user "Package Geometry/Place Bound Bottom")
		(35 "F.Fab" user "Ref Des/Assembly Top")
		(33 "B.Fab" user "Ref Des/Assembly Bottom")
	)
	(footprint ""
		(layer "F.Cu")
		(at 337.142328 -19.434556 -90)
		(property "Reference" "U60"
			(at 2.376678 -2.681732 0)
			(unlocked yes)
			(layer "F.SilkS")
			(effects
				(font
					(size 0.7874 0.5842)
					(thickness 0.1524)
				)
			)
		)
		(property "Value" ""
			(at 0 0 270)
			(layer "F.Fab")
			(effects
				(font
					(size 1.27 1.27)
				)
			)
		)
		(duplicate_pad_numbers_are_jumpers no)
		(fp_line
			(start -1.7272 1.1176)
			(end -1.7272 -1.1176)
			(stroke
				(width 0.1524)
				(type default)
			)
			(layer "F.SilkS")
		)
		(fp_line
			(start 1.7272 1.1176)
			(end -1.7272 1.1176)
			(stroke
				(width 0.1524)
				(type default)
			)
			(layer "F.SilkS")
		)
		(fp_line
			(start 0 -0.7366)
			(end -0.254 -1.1176)
			(stroke
				(width 0.1524)
				(type default)
			)
			(layer "F.SilkS")
		)
		(fp_line
			(start -0.254 -1.1176)
			(end -1.7272 -1.1176)
			(stroke
				(width 0.1524)
				(type default)
			)
			(layer "F.SilkS")
		)
		(fp_line
			(start 0.254 -1.1176)
			(end 0 -0.7366)
			(stroke
				(width 0.1524)
				(type default)
			)
			(layer "F.SilkS")
		)
		(fp_line
			(start 1.7272 -1.1176)
			(end 1.7272 1.1176)
			(stroke
				(width 0.1524)
				(type default)
			)
			(layer "F.SilkS")
		)
		(fp_line
			(start 1.7272 -1.1176)
			(end 0.254 -1.1176)
			(stroke
				(width 0.1524)
				(type default)
			)
			(layer "F.SilkS")
		)
		(fp_poly
			(pts
				(xy -1.458214 -2.053336) (xy -0.696214 -2.053336) (xy -1.077214 -1.291336)
			)
			(stroke
				(width 0)
				(type default)
			)
			(fill yes)
			(layer "F.SilkS")
		)
		(fp_line
			(start -1.5748 1.1176)
			(end 1.5748 1.1176)
			(stroke
				(width 0.1)
				(type default)
			)
			(layer "F.Fab")
		)
		(fp_line
			(start 1.5748 1.1176)
			(end 1.5748 -1.1176)
			(stroke
				(width 0.1)
				(type default)
			)
			(layer "F.Fab")
		)
		(fp_line
			(start -1.5748 -1.1176)
			(end -1.5748 1.1176)
			(stroke
				(width 0.1)
				(type default)
			)
			(layer "F.Fab")
		)
		(fp_line
			(start 1.5748 -1.1176)
			(end -1.5748 -1.1176)
			(stroke
				(width 0.1)
				(type default)
			)
			(layer "F.Fab")
		)
		(fp_poly
			(pts
				(xy -1.9558 -0.649986) (xy -2.7178 -0.268986) (xy -2.7178 -1.030986)
			)
			(stroke
				(width 0)
				(type default)
			)
			(fill yes)
			(layer "F.Fab")
		)
		(pad "1" smd rect
			(at -0.999998 -0.649986 180)
			(size 0.3556 1.1176)
			(layers "F.Cu" "F.Mask" "F.Paste")
			(net "IRQ_LPC_PIRQA_N_ESPI_ALERT0_R_N")
		)
		(pad "2" smd rect
			(at -0.999998 0 180)
			(size 0.3556 1.1176)
			(layers "F.Cu" "F.Mask" "F.Paste")
			(net "GND")
		)
		(pad "3" smd rect
			(at -0.999998 0.649986 180)
			(size 0.3556 1.1176)
			(layers "F.Cu" "F.Mask" "F.Paste")
			(net "IRQ_LPC_SERIRQ_ESPI_CS1_R_N")
		)
		(pad "4" smd rect
			(at 0.999998 0.649986 180)
			(size 0.3556 1.1176)
			(layers "F.Cu" "F.Mask" "F.Paste")
			(net "IRQ_ESPI_LPC_SERIRQ_ALERT_N")
		)
		(pad "5" smd rect
			(at 0.999998 0 180)
			(size 0.3556 1.1176)
			(layers "F.Cu" "F.Mask" "F.Paste")
			(net "PGPPA_AUX")
		)
		(pad "6" smd rect
			(at 0.999998 -0.649986 180)
			(size 0.3556 1.1176)
			(layers "F.Cu" "F.Mask" "F.Paste")
			(net "FM_ESPI_PLD_EN")
		)
	)
	(footprint ""
		(layer "F.Cu")
		(at 249.713496 -47.078138)
		(property "Reference" "PC2217"
			(at 0 0 0)
			(layer "F.SilkS")
			(hide yes)
			(effects
				(font
					(size 1.27 1.27)
				)
			)
		)
		(property "Value" ""
			(at 0 0 0)
			(layer "F.Fab")
			(effects
				(font
					(size 1.27 1.27)
				)
			)
		)
		(duplicate_pad_numbers_are_jumpers no)
		(fp_line
			(start -0.7874 -0.4064)
			(end 0.7874 -0.4064)
			(stroke
				(width 0.1524)
				(type default)
			)
			(layer "F.SilkS")
		)
		(fp_line
			(start -0.7874 0.4064)
			(end -0.7874 -0.4064)
			(stroke
				(width 0.1524)
				(type default)
			)
			(layer "F.SilkS")
		)
		(fp_line
			(start 0.7874 -0.4064)
			(end 0.7874 0.4064)
			(stroke
				(width 0.1524)
				(type default)
			)
			(layer "F.SilkS")
		)
		(fp_line
			(start 0.7874 0.4064)
			(end -0.7874 0.4064)
			(stroke
				(width 0.1524)
				(type default)
			)
			(layer "F.SilkS")
		)
		(fp_line
			(start -0.67945 -0.305054)
			(end -0.12065 -0.305054)
			(stroke
				(width 0.1)
				(type default)
			)
			(layer "F.Fab")
		)
		(fp_line
			(start -0.67945 0.3048)
			(end -0.67945 -0.305054)
			(stroke
				(width 0.1)
				(type default)
			)
			(layer "F.Fab")
		)
		(fp_line
			(start -0.12065 -0.305054)
			(end -0.12065 -0.2794)
			(stroke
				(width 0.1)
				(type default)
			)
			(layer "F.Fab")
		)
		(fp_line
			(start -0.12065 -0.2794)
			(end 0.12065 -0.2794)
			(stroke
				(width 0.1)
				(type default)
			)
			(layer "F.Fab")
		)
		(fp_line
			(start -0.12065 0.2794)
			(end -0.12065 0.3048)
			(stroke
				(width 0.1)
				(type default)
			)
			(layer "F.Fab")
		)
		(fp_line
			(start -0.12065 0.3048)
			(end -0.67945 0.3048)
			(stroke
				(width 0.1)
				(type default)
			)
			(layer "F.Fab")
		)
		(fp_line
			(start 0.120396 0.2794)
			(end -0.12065 0.2794)
			(stroke
				(width 0.1)
				(type default)
			)
			(layer "F.Fab")
		)
		(fp_line
			(start 0.120396 0.3048)
			(end 0.120396 0.2794)
			(stroke
				(width 0.1)
				(type default)
			)
			(layer "F.Fab")
		)
		(fp_line
			(start 0.12065 -0.3048)
			(end 0.67945 -0.3048)
			(stroke
				(width 0.1)
				(type default)
			)
			(layer "F.Fab")
		)
		(fp_line
			(start 0.12065 -0.2794)
			(end 0.12065 -0.3048)
			(stroke
				(width 0.1)
				(type default)
			)
			(layer "F.Fab")
		)
		(fp_line
			(start 0.67945 -0.3048)
			(end 0.67945 0.3048)
			(stroke
				(width 0.1)
				(type default)
			)
			(layer "F.Fab")
		)
		(fp_line
			(start 0.67945 0.3048)
			(end 0.120396 0.3048)
			(stroke
				(width 0.1)
				(type default)
			)
			(layer "F.Fab")
		)
		(pad "1" smd circle
			(at -0.40005 0)
			(size 0 0)
			(layers "F.Cu" "F.Mask" "F.Paste")
			(net "P12V_E1S_0")
		)
		(pad "2" smd circle
			(at 0.40005 0)
			(size 0 0)
			(layers "F.Cu" "F.Mask" "F.Paste")
			(net "GND")
		)
	)
	(footprint ""
		(layer "F.Cu")
		(at 287.2994 -346.700348)
		(property "Reference" "PC621"
			(at 0 0 0)
			(layer "F.SilkS")
			(hide yes)
			(effects
				(font
					(size 1.27 1.27)
				)
			)
		)
		(property "Value" ""
			(at 0 0 0)
			(layer "F.Fab")
			(effects
				(font
					(size 1.27 1.27)
				)
			)
		)
		(duplicate_pad_numbers_are_jumpers no)
		(fp_line
			(start 2.750058 0.999998)
			(end -2.750058 0.999998)
			(stroke
				(width 0.1524)
				(type default)
			)
			(layer "F.SilkS")
		)
		(fp_circle
			(center 0 0.999998)
			(end 2.750058 0.999998)
			(stroke
				(width 0.1524)
				(type default)
			)
			(fill no)
			(layer "F.SilkS")
		)
		(fp_poly
			(pts
				(arc
					(start 2.750058 0.999998)
					(mid 0 3.750056)
					(end -2.750058 0.999998)
				)
			)
			(stroke
				(width 0)
				(type default)
			)
			(fill yes)
			(layer "F.SilkS")
		)
		(fp_circle
			(center 0 0.999998)
			(end 2.750058 0.999998)
			(stroke
				(width 0.1)
				(type default)
			)
			(fill no)
			(layer "F.Fab")
		)
		(pad "1" thru_hole rect
			(at 0 0)
			(size 1.5748 1.5748)
			(drill 1.0668)
			(layers "*.Cu" "*.Mask")
			(remove_unused_layers no)
			(net "PVCCFA_EHV_FIVRA_CPU0")
			(clearance 0)
			(padstack
				(mode front_inner_back)
				(layer "Inner"
					(shape circle)
					(size 1.5748 1.5748)
					(clearance 0)
				)
				(layer "B.Cu"
					(shape rect)
					(size 1.5748 1.5748)
					(clearance 0)
				)
			)
		)
		(pad "2" thru_hole circle
			(at 0 1.999996)
			(size 1.5748 1.5748)
			(drill 1.0668)
			(layers "*.Cu" "*.Mask")
			(remove_unused_layers no)
			(net "GND")
			(clearance 0)
		)
	)
	(footprint ""
		(layer "F.Cu")
		(at 393.37488 -148.808948 90)
		(property "Reference" "R977"
			(at 0 0 90)
			(layer "F.SilkS")
			(hide yes)
			(effects
				(font
					(size 1.27 1.27)
				)
			)
		)
		(property "Value" ""
			(at 0 0 90)
			(layer "F.Fab")
			(effects
				(font
					(size 1.27 1.27)
				)
			)
		)
		(duplicate_pad_numbers_are_jumpers no)
		(fp_line
			(start 0.7874 -0.4064)
			(end 0.7874 0.4064)
			(stroke
				(width 0.1524)
				(type default)
			)
			(layer "F.SilkS")
		)
		(fp_line
			(start -0.7874 -0.4064)
			(end 0.7874 -0.4064)
			(stroke
				(width 0.1524)
				(type default)
			)
			(layer "F.SilkS")
		)
		(fp_line
			(start 0.7874 0.4064)
			(end -0.7874 0.4064)
			(stroke
				(width 0.1524)
				(type default)
			)
			(layer "F.SilkS")
		)
		(fp_line
			(start -0.7874 0.4064)
			(end -0.7874 -0.4064)
			(stroke
				(width 0.1524)
				(type default)
			)
			(layer "F.SilkS")
		)
		(fp_line
			(start -0.12065 -0.305054)
			(end -0.12065 -0.2794)
			(stroke
				(width 0.1)
				(type default)
			)
			(layer "F.Fab")
		)
		(fp_line
			(start -0.67945 -0.305054)
			(end -0.12065 -0.305054)
			(stroke
				(width 0.1)
				(type default)
			)
			(layer "F.Fab")
		)
		(fp_line
			(start 0.67945 -0.3048)
			(end 0.67945 0.3048)
			(stroke
				(width 0.1)
				(type default)
			)
			(layer "F.Fab")
		)
		(fp_line
			(start 0.12065 -0.3048)
			(end 0.67945 -0.3048)
			(stroke
				(width 0.1)
				(type default)
			)
			(layer "F.Fab")
		)
		(fp_line
			(start 0.12065 -0.2794)
			(end 0.12065 -0.3048)
			(stroke
				(width 0.1)
				(type default)
			)
			(layer "F.Fab")
		)
		(fp_line
			(start -0.12065 -0.2794)
			(end 0.12065 -0.2794)
			(stroke
				(width 0.1)
				(type default)
			)
			(layer "F.Fab")
		)
		(fp_line
			(start 0.120396 0.2794)
			(end -0.12065 0.2794)
			(stroke
				(width 0.1)
				(type default)
			)
			(layer "F.Fab")
		)
		(fp_line
			(start -0.12065 0.2794)
			(end -0.12065 0.3048)
			(stroke
				(width 0.1)
				(type default)
			)
			(layer "F.Fab")
		)
		(fp_line
			(start 0.67945 0.3048)
			(end 0.120396 0.3048)
			(stroke
				(width 0.1)
				(type default)
			)
			(layer "F.Fab")
		)
		(fp_line
			(start 0.120396 0.3048)
			(end 0.120396 0.2794)
			(stroke
				(width 0.1)
				(type default)
			)
			(layer "F.Fab")
		)
		(fp_line
			(start -0.12065 0.3048)
			(end -0.67945 0.3048)
			(stroke
				(width 0.1)
				(type default)
			)
			(layer "F.Fab")
		)
		(fp_line
			(start -0.67945 0.3048)
			(end -0.67945 -0.305054)
			(stroke
				(width 0.1)
				(type default)
			)
			(layer "F.Fab")
		)
		(pad "1" smd circle
			(at -0.40005 0 90)
			(size 0 0)
			(layers "F.Cu" "F.Mask" "F.Paste")
			(net "P3V3_AUX")
		)
		(pad "2" smd circle
			(at 0.40005 0 90)
			(size 0 0)
			(layers "F.Cu" "F.Mask" "F.Paste")
			(net "SMB_S3M_CPU0_3V3AUX_SCL")
		)
	)
	(footprint ""
		(layer "F.Cu")
		(at 41.573958 -344.77325 -90)
		(property "Reference" "PL113"
			(at 2.130552 8.226298 0)
			(unlocked yes)
			(layer "F.SilkS")
			(effects
				(font
					(size 0.7874 0.5842)
					(thickness 0.1524)
				)
				(justify left)
			)
		)
		(property "Value" ""
			(at 0 0 270)
			(layer "F.Fab")
			(effects
				(font
					(size 1.27 1.27)
				)
			)
		)
		(duplicate_pad_numbers_are_jumpers no)
		(fp_line
			(start -4.99999 3.750056)
			(end -4.99999 2.2479)
			(stroke
				(width 0.1524)
				(type default)
			)
			(layer "F.SilkS")
		)
		(fp_line
			(start 0 3.750056)
			(end -4.99999 3.750056)
			(stroke
				(width 0.1524)
				(type default)
			)
			(layer "F.SilkS")
		)
		(fp_line
			(start 4.99999 3.750056)
			(end 0 3.750056)
			(stroke
				(width 0.1524)
				(type default)
			)
			(layer "F.SilkS")
		)
		(fp_line
			(start 4.99999 2.2352)
			(end 4.99999 3.750056)
			(stroke
				(width 0.1524)
				(type default)
			)
			(layer "F.SilkS")
		)
		(fp_line
			(start -4.99999 -2.2479)
			(end -4.99999 -3.750056)
			(stroke
				(width 0.1524)
				(type default)
			)
			(layer "F.SilkS")
		)
		(fp_line
			(start -4.99999 -3.750056)
			(end 4.99999 -3.750056)
			(stroke
				(width 0.1524)
				(type default)
			)
			(layer "F.SilkS")
		)
		(fp_line
			(start 4.99999 -3.750056)
			(end 4.99999 -2.2479)
			(stroke
				(width 0.1524)
				(type default)
			)
			(layer "F.SilkS")
		)
		(fp_line
			(start -4.99999 3.750056)
			(end -4.99999 -3.750056)
			(stroke
				(width 0.1)
				(type default)
			)
			(layer "F.Fab")
		)
		(fp_line
			(start 0 3.750056)
			(end -4.99999 3.750056)
			(stroke
				(width 0.1)
				(type default)
			)
			(layer "F.Fab")
		)
		(fp_line
			(start 4.99999 3.750056)
			(end 0 3.750056)
			(stroke
				(width 0.1)
				(type default)
			)
			(layer "F.Fab")
		)
		(fp_line
			(start -4.99999 -3.750056)
			(end 4.99999 -3.750056)
			(stroke
				(width 0.1)
				(type default)
			)
			(layer "F.Fab")
		)
		(fp_line
			(start 4.99999 -3.750056)
			(end 4.99999 3.750056)
			(stroke
				(width 0.1)
				(type default)
			)
			(layer "F.Fab")
		)
		(pad "1" smd rect
			(at -3.299968 0 270)
			(size 3.302 4.2164)
			(layers "F.Cu" "F.Mask" "F.Paste")
			(net "SW_PVCCFA_EHV_FIVRA_CPU1_SW4")
		)
		(pad "2" smd rect
			(at 3.299968 0 270)
			(size 3.302 4.2164)
			(layers "F.Cu" "F.Mask" "F.Paste")
			(net "PVCCFA_EHV_FIVRA_CPU1")
		)
	)
	(footprint ""
		(layer "F.Cu")
		(at 113.494312 -132.456682 180)
		(property "Reference" "R3393"
			(at 0 0 180)
			(layer "F.SilkS")
			(hide yes)
			(effects
				(font
					(size 1.27 1.27)
				)
			)
		)
		(property "Value" ""
			(at 0 0 180)
			(layer "F.Fab")
			(effects
				(font
					(size 1.27 1.27)
				)
			)
		)
		(duplicate_pad_numbers_are_jumpers no)
		(fp_line
			(start 0.7874 0.4064)
			(end -0.7874 0.4064)
			(stroke
				(width 0.1524)
				(type default)
			)
			(layer "F.SilkS")
		)
		(fp_line
			(start 0.7874 -0.4064)
			(end 0.7874 0.4064)
			(stroke
				(width 0.1524)
				(type default)
			)
			(layer "F.SilkS")
		)
		(fp_line
			(start -0.7874 0.4064)
			(end -0.7874 -0.4064)
			(stroke
				(width 0.1524)
				(type default)
			)
			(layer "F.SilkS")
		)
		(fp_line
			(start -0.7874 -0.4064)
			(end 0.7874 -0.4064)
			(stroke
				(width 0.1524)
				(type default)
			)
			(layer "F.SilkS")
		)
		(fp_line
			(start 0.67945 0.3048)
			(end 0.120396 0.3048)
			(stroke
				(width 0.1)
				(type default)
			)
			(layer "F.Fab")
		)
		(fp_line
			(start 0.67945 -0.3048)
			(end 0.67945 0.3048)
			(stroke
				(width 0.1)
				(type default)
			)
			(layer "F.Fab")
		)
		(fp_line
			(start 0.12065 -0.2794)
			(end 0.12065 -0.3048)
			(stroke
				(width 0.1)
				(type default)
			)
			(layer "F.Fab")
		)
		(fp_line
			(start 0.12065 -0.3048)
			(end 0.67945 -0.3048)
			(stroke
				(width 0.1)
				(type default)
			)
			(layer "F.Fab")
		)
		(fp_line
			(start 0.120396 0.3048)
			(end 0.120396 0.2794)
			(stroke
				(width 0.1)
				(type default)
			)
			(layer "F.Fab")
		)
		(fp_line
			(start 0.120396 0.2794)
			(end -0.12065 0.2794)
			(stroke
				(width 0.1)
				(type default)
			)
			(layer "F.Fab")
		)
		(fp_line
			(start -0.12065 0.3048)
			(end -0.67945 0.3048)
			(stroke
				(width 0.1)
				(type default)
			)
			(layer "F.Fab")
		)
		(fp_line
			(start -0.12065 0.2794)
			(end -0.12065 0.3048)
			(stroke
				(width 0.1)
				(type default)
			)
			(layer "F.Fab")
		)
		(fp_line
			(start -0.12065 -0.2794)
			(end 0.12065 -0.2794)
			(stroke
				(width 0.1)
				(type default)
			)
			(layer "F.Fab")
		)
		(fp_line
			(start -0.12065 -0.305054)
			(end -0.12065 -0.2794)
			(stroke
				(width 0.1)
				(type default)
			)
			(layer "F.Fab")
		)
		(fp_line
			(start -0.67945 0.3048)
			(end -0.67945 -0.305054)
			(stroke
				(width 0.1)
				(type default)
			)
			(layer "F.Fab")
		)
		(fp_line
			(start -0.67945 -0.305054)
			(end -0.12065 -0.305054)
			(stroke
				(width 0.1)
				(type default)
			)
			(layer "F.Fab")
		)
		(pad "1" smd circle
			(at -0.40005 0 180)
			(size 0 0)
			(layers "F.Cu" "F.Mask" "F.Paste")
			(net "SMB_IOEXP_3V3AUX_SCL_R")
		)
		(pad "2" smd circle
			(at 0.40005 0 180)
			(size 0 0)
			(layers "F.Cu" "F.Mask" "F.Paste")
			(net "SMB_IOEXP_3V3AUX_SCL")
		)
	)
)
